(kicad_pcb
	(version 20241229)
	(generator "pcbnew")
	(generator_version "9.0")
	(general
		(thickness 1.62)
		(legacy_teardrops no)
	)
	(paper "A3")
	(title_block
		(title "COM Express 7 Baseboard")
		(date "2025-02-04")
		(rev "1.1.2")
		(company "Antmicro Ltd")
		(comment 1 "www.antmicro.com")
		(comment 9 "footprint 489 of 802 (J12), pads 448-450 of 450")
	)
	(layers
		(0 "F.Cu" signal)
		(4 "In1.Cu" signal)
		(6 "In2.Cu" signal)
		(8 "In3.Cu" signal)
		(10 "In4.Cu" signal)
		(12 "In5.Cu" signal)
		(14 "In6.Cu" signal)
		(2 "B.Cu" signal)
		(9 "F.Adhes" user "F.Adhesive")
		(11 "B.Adhes" user "B.Adhesive")
		(13 "F.Paste" user)
		(15 "B.Paste" user)
		(5 "F.SilkS" user "F.Silkscreen")
		(7 "B.SilkS" user "B.Silkscreen")
		(1 "F.Mask" user)
		(3 "B.Mask" user)
		(17 "Dwgs.User" user "User.Drawings")
		(19 "Cmts.User" user "User.Comments")
		(21 "Eco1.User" user "User.Eco1")
		(23 "Eco2.User" user "User.Eco2")
		(25 "Edge.Cuts" user)
		(27 "Margin" user)
		(31 "F.CrtYd" user "F.Courtyard")
		(29 "B.CrtYd" user "B.Courtyard")
		(35 "F.Fab" user)
		(33 "B.Fab" user)
	)
	(footprint "antmicro-footprints:EPT_401-51501-51"
		(layer "F.Cu")
		(at 203.275 159.81)
		(property "Reference" "J12"
			(at 30.975 -10.45 0)
			(layer "F.SilkS")
			(effects
				(font
					(size 0.7 0.7)
					(thickness 0.15)
				)
				(justify right top)
			)
		)
		(property "Value" "Plug_Bus_CE7_EPT_401-51501-51"
			(at -3.225 52.665 0)
			(layer "F.Fab")
			(hide yes)
			(effects
				(font
					(size 0.7 0.7)
					(thickness 0.15)
				)
				(justify left top)
			)
		)
		(property "Datasheet" "https://www.farnell.com/datasheets/1905093.pdf"
			(at 0 0 0)
			(layer "F.Fab")
			(hide yes)
			(effects
				(font
					(size 1.27 1.27)
					(thickness 0.15)
				)
			)
		)
		(property "Author" "Antmicro"
			(at 406.55 319.62 0)
			(layer "F.Fab")
			(hide yes)
			(effects
				(font
					(size 1 1)
					(thickness 0.15)
				)
			)
		)
		(property "License" "Apache-2.0"
			(at 406.55 319.62 0)
			(layer "F.Fab")
			(hide yes)
			(effects
				(font
					(size 1 1)
					(thickness 0.15)
				)
			)
		)
		(property "MPN" "401-51501-51"
			(at 406.55 319.62 0)
			(layer "F.Fab")
			(hide yes)
			(effects
				(font
					(size 1 1)
					(thickness 0.15)
				)
			)
		)
		(property "Manufacturer" "ept"
			(at 406.55 319.62 0)
			(layer "F.Fab")
			(hide yes)
			(effects
				(font
					(size 1 1)
					(thickness 0.15)
				)
			)
		)
		(sheetname "Com Express 7 Interfaces")
		(sheetfile "com_express_7_interfaces.kicad_sch")
		(attr smd)
		(pad "MP" smd rect
			(at 30.575 6 90)
			(size 0.001 0.001)
			(layers "F.Cu" "F.Mask" "F.Paste")
			(net 1 "GND")
			(pinfunction "MP")
			(pintype "passive")
			(teardrops
				(best_length_ratio 0.2)
				(max_length 1)
				(best_width_ratio 0.9)
				(max_width 2)
				(curved_edges yes)
				(filter_ratio 0.9)
				(enabled yes)
				(allow_two_segments yes)
				(prefer_zone_connections yes)
			)
		)
		(pad "MP" smd rect
			(at 30.65 -6 90)
			(size 3.3 1.6)
			(layers "F.Cu" "F.Mask" "F.Paste")
			(net 1 "GND")
			(pinfunction "MP")
			(pintype "passive")
			(teardrops
				(best_length_ratio 0.2)
				(max_length 1)
				(best_width_ratio 0.9)
				(max_width 2)
				(curved_edges yes)
				(filter_ratio 0.9)
				(enabled yes)
				(allow_two_segments yes)
				(prefer_zone_connections yes)
			)
		)
		(pad "MP" smd rect
			(at 30.65 5.9995 90)
			(size 3.3 1.6)
			(layers "F.Cu" "F.Mask" "F.Paste")
			(net 1 "GND")
			(pinfunction "MP")
			(pintype "passive")
			(teardrops
				(best_length_ratio 0.2)
				(max_length 1)
				(best_width_ratio 0.9)
				(max_width 2)
				(curved_edges yes)
				(filter_ratio 0.9)
				(enabled yes)
				(allow_two_segments yes)
				(prefer_zone_connections yes)
			)
		)
	)
)
